# BASEBOARD_FAB2 (Tioga Pass) — schematic netlist excerpt (pin names and nets, part order shuffled) for the footprints in the layout excerpt that follows; sources: Cadence DE-HDL packaged netlist, KiCad conversion of Wiwynn_Tioga_Pass_MB.brd

C5G69  CAP_A  22.0UF 4V 20% X6S  pkg 0603V  page 242 : A = PVDDQ_DEF ; B = GND
C8U7  CAP_A  47UF 4V 20% X5R  pkg 0603V  page 225 : A = PVDDQ_GHJ ; B = GND
R6P33  RES  110 1% EMPTY  pkg 0402  page 213 : A = PVCCIO_CPU1 ; B = SVID_CLK0_CPU1_R

(kicad_pcb
	(version 20260206)
	(generator "pcbnew")
	(generator_version "10.0")
	(general
		(thickness 1.6)
		(legacy_teardrops no)
	)
	(paper "A4")
	(title_block
		(title "Wiwynn_Tioga_Pass_MB.brd")
		(comment 1 "Tioga Pass / footprints 3697-3699 of 4770")
	)
	(layers
		(0 "F.Cu" signal "TOP")
		(4 "In1.Cu" signal "L2GND")
		(6 "In2.Cu" signal "L3")
		(8 "In3.Cu" signal "L4GND")
		(10 "In4.Cu" signal "L5")
		(12 "In5.Cu" signal "L6GND")
		(14 "In6.Cu" signal "L7VCC")
		(16 "In7.Cu" signal "L8VCC")
		(18 "In8.Cu" signal "L9GND")
		(20 "In9.Cu" signal "L10")
		(22 "In10.Cu" signal "L11GND")
		(24 "In11.Cu" signal "L12")
		(26 "In12.Cu" signal "L13GND")
		(2 "B.Cu" signal "BOTTOM")
		(9 "F.Adhes" user "F.Adhesive")
		(11 "B.Adhes" user "B.Adhesive")
		(13 "F.Paste" user "Package Geometry/Pastemask Top")
		(15 "B.Paste" user "Package Geometry/Pastemask Bottom")
		(5 "F.SilkS" user "Ref Des/Silkscreen Top")
		(7 "B.SilkS" user "Ref Des/Silkscreen Bottom")
		(1 "F.Mask" user "Board Geometry/Soldermask Top")
		(3 "B.Mask" user "Board Geometry/Soldermask Bottom")
		(17 "Dwgs.User" user "User.Drawings")
		(19 "Cmts.User" user "User.Comments")
		(21 "Eco1.User" user "User.Eco1")
		(23 "Eco2.User" user "User.Eco2")
		(25 "Edge.Cuts" user "Board Geometry/Outline")
		(27 "Margin" user)
		(31 "F.CrtYd" user "Package Geometry/Place Bound Top")
		(29 "B.CrtYd" user "Package Geometry/Place Bound Bottom")
		(35 "F.Fab" user "Ref Des/Assembly Top")
		(33 "B.Fab" user "Ref Des/Assembly Bottom")
	)
	(footprint ""
		(layer "B.Cu")
		(at 80.757268 -8.1534 -90)
		(property "Reference" "C8U7"
			(at -1.848866 0.752348 270)
			(unlocked yes)
			(layer "B.SilkS")
			(effects
				(font
					(size 1.27 0.9652)
					(thickness 0.1524)
				)
				(justify mirror)
			)
		)
		(property "Value" ""
			(at 0 0 90)
			(layer "B.Fab")
			(effects
				(font
					(size 1.27 1.27)
				)
				(justify mirror)
			)
		)
		(duplicate_pad_numbers_are_jumpers no)
		(fp_rect
			(start 0.500126 1.598422)
			(end -0.500126 -0.201422)
			(stroke
				(width 0)
				(type default)
			)
			(fill no)
			(layer "B.CrtYd")
		)
		(fp_line
			(start -0.500126 1.598422)
			(end 0.500126 1.598422)
			(stroke
				(width 0.1)
				(type default)
			)
			(layer "B.Fab")
		)
		(fp_line
			(start 0.500126 1.598422)
			(end 0.500126 -0.201422)
			(stroke
				(width 0.1)
				(type default)
			)
			(layer "B.Fab")
		)
		(fp_line
			(start -0.500126 -0.201422)
			(end -0.500126 1.598422)
			(stroke
				(width 0.1)
				(type default)
			)
			(layer "B.Fab")
		)
		(fp_line
			(start 0.500126 -0.201422)
			(end -0.500126 -0.201422)
			(stroke
				(width 0.1)
				(type default)
			)
			(layer "B.Fab")
		)
		(pad "1" smd rect
			(at 0 0 180)
			(size 0.889 0.9906)
			(layers "B.Cu" "B.Mask" "B.Paste")
			(net "PVDDQ_GHJ")
		)
		(pad "2" smd rect
			(at 0 1.397 180)
			(size 0.889 0.9906)
			(layers "B.Cu" "B.Mask" "B.Paste")
			(net "GND")
		)
		(zone
			(layer "B.Cu")
			(hatch none 0.5)
			(connect_pads
				(clearance 0)
			)
			(min_thickness 0.25)
			(keepout
				(tracks not_allowed)
				(vias allowed)
				(pads allowed)
				(copperpour not_allowed)
				(footprints allowed)
			)
			(placement
				(enabled no)
				(sheetname "")
			)
			(fill
				(thermal_gap 0.5)
				(thermal_bridge_width 0.5)
				(island_removal_mode 0)
			)
			(polygon
				(pts
					(xy 79.804768 -7.6581) (xy 80.312768 -7.6581) (xy 80.312768 -8.6487) (xy 79.804768 -8.6487)
				)
			)
		)
		(zone
			(layer "B.Cu")
			(hatch none 0.5)
			(connect_pads
				(clearance 0)
			)
			(min_thickness 0.25)
			(keepout
				(tracks allowed)
				(vias not_allowed)
				(pads allowed)
				(copperpour not_allowed)
				(footprints allowed)
			)
			(placement
				(enabled no)
				(sheetname "")
			)
			(fill
				(thermal_gap 0.5)
				(thermal_bridge_width 0.5)
				(island_removal_mode 0)
			)
			(polygon
				(pts
					(xy 79.804768 -7.6581) (xy 80.312768 -7.6581) (xy 80.312768 -8.6487) (xy 79.804768 -8.6487)
				)
			)
		)
	)
	(footprint ""
		(layer "B.Cu")
		(at 266.397232 -149.8092 90)
		(property "Reference" "C5G69"
			(at -1.14681 0.76708 180)
			(unlocked yes)
			(layer "B.SilkS")
			(effects
				(font
					(size 0.7874 0.5842)
					(thickness 0.1524)
				)
				(justify mirror)
			)
		)
		(property "Value" ""
			(at 0 0 90)
			(layer "B.Fab")
			(effects
				(font
					(size 1.27 1.27)
				)
				(justify mirror)
			)
		)
		(duplicate_pad_numbers_are_jumpers no)
		(fp_rect
			(start -0.4953 -0.2032)
			(end 0.4953 1.6002)
			(stroke
				(width 0)
				(type default)
			)
			(fill no)
			(layer "B.CrtYd")
		)
		(fp_line
			(start 0.4953 -0.2032)
			(end -0.4953 -0.2032)
			(stroke
				(width 0.1)
				(type default)
			)
			(layer "B.Fab")
		)
		(fp_line
			(start -0.4953 -0.2032)
			(end -0.4953 1.6002)
			(stroke
				(width 0.1)
				(type default)
			)
			(layer "B.Fab")
		)
		(fp_line
			(start 0.4953 1.6002)
			(end 0.4953 -0.2032)
			(stroke
				(width 0.1)
				(type default)
			)
			(layer "B.Fab")
		)
		(fp_line
			(start -0.4953 1.6002)
			(end 0.4953 1.6002)
			(stroke
				(width 0.1)
				(type default)
			)
			(layer "B.Fab")
		)
		(pad "1" smd rect
			(at 0 0 270)
			(size 0.762 0.889)
			(layers "B.Cu" "B.Mask" "B.Paste")
			(net "PVDDQ_DEF")
		)
		(pad "2" smd rect
			(at 0 1.397 270)
			(size 0.762 0.889)
			(layers "B.Cu" "B.Mask" "B.Paste")
			(net "GND")
		)
		(zone
			(layer "B.Cu")
			(hatch none 0.5)
			(connect_pads
				(clearance 0)
			)
			(min_thickness 0.25)
			(keepout
				(tracks not_allowed)
				(vias allowed)
				(pads allowed)
				(copperpour not_allowed)
				(footprints allowed)
			)
			(placement
				(enabled no)
				(sheetname "")
			)
			(fill
				(thermal_gap 0.5)
				(thermal_bridge_width 0.5)
				(island_removal_mode 0)
			)
			(polygon
				(pts
					(xy 266.841732 -149.4282) (xy 267.349732 -149.4282) (xy 267.349732 -150.1902) (xy 266.841732 -150.1902)
				)
			)
		)
	)
	(footprint ""
		(layer "B.Cu")
		(at 164.973 -69.088 -90)
		(property "Reference" "R6P33"
			(at 0 0 90)
			(layer "B.SilkS")
			(hide yes)
			(effects
				(font
					(size 1.27 1.27)
				)
				(justify mirror)
			)
		)
		(property "Value" ""
			(at 0 0 90)
			(layer "B.Fab")
			(effects
				(font
					(size 1.27 1.27)
				)
				(justify mirror)
			)
		)
		(duplicate_pad_numbers_are_jumpers no)
		(fp_poly
			(pts
				(xy 0.2794 -0.1016) (xy -0.2794 -0.1016) (xy -0.2794 0.9906) (xy 0.2794 0.9906)
			)
			(stroke
				(width 0)
				(type default)
			)
			(fill no)
			(layer "B.CrtYd")
		)
		(fp_line
			(start -0.2794 0.9906)
			(end -0.2794 -0.1016)
			(stroke
				(width 0.1)
				(type default)
			)
			(layer "B.Fab")
		)
		(fp_line
			(start 0.2794 0.9906)
			(end -0.2794 0.9906)
			(stroke
				(width 0.1)
				(type default)
			)
			(layer "B.Fab")
		)
		(fp_line
			(start -0.2794 -0.1016)
			(end 0.2794 -0.1016)
			(stroke
				(width 0.1)
				(type default)
			)
			(layer "B.Fab")
		)
		(fp_line
			(start 0.2794 -0.1016)
			(end 0.2794 0.9906)
			(stroke
				(width 0.1)
				(type default)
			)
			(layer "B.Fab")
		)
		(pad "1" smd rect
			(at 0 0 90)
			(size 0.508 0.508)
			(layers "B.Cu" "B.Mask" "B.Paste")
			(net "PVCCIO_CPU1")
		)
		(pad "2" smd rect
			(at 0 0.889 90)
			(size 0.508 0.508)
			(layers "B.Cu" "B.Mask" "B.Paste")
			(net "SVID_CLK0_CPU1_R")
		)
		(zone
			(layer "B.Cu")
			(hatch none 0.5)
			(connect_pads
				(clearance 0)
			)
			(min_thickness 0.25)
			(keepout
				(tracks not_allowed)
				(vias allowed)
				(pads allowed)
				(copperpour not_allowed)
				(footprints allowed)
			)
			(placement
				(enabled no)
				(sheetname "")
			)
			(fill
				(thermal_gap 0.5)
				(thermal_bridge_width 0.5)
				(island_removal_mode 0)
			)
			(polygon
				(pts
					(xy 164.338 -68.834) (xy 164.338 -69.342) (xy 164.719 -69.342) (xy 164.719 -68.834)
				)
			)
		)
		(zone
			(layer "B.Cu")
			(hatch none 0.5)
			(connect_pads
				(clearance 0)
			)
			(min_thickness 0.25)
			(keepout
				(tracks allowed)
				(vias not_allowed)
				(pads allowed)
				(copperpour not_allowed)
				(footprints allowed)
			)
			(placement
				(enabled no)
				(sheetname "")
			)
			(fill
				(thermal_gap 0.5)
				(thermal_bridge_width 0.5)
				(island_removal_mode 0)
			)
			(polygon
				(pts
					(xy 164.719 -68.834) (xy 164.719 -69.342) (xy 164.338 -69.342) (xy 164.338 -68.834)
				)
			)
		)
	)
)
